(kicad_pcb
	(version 20241229)
	(generator "pcbnew")
	(generator_version "9.0")
	(general
		(thickness 1.61)
		(legacy_teardrops no)
	)
	(paper "A3")
	(title_block
		(title "RDIMM DDR5 Tester")
		(date "2026-05-21")
		(rev "2.2.0")
		(company "Antmicro")
		(comment 9 "footprints 440-444 of 796")
	)
	(layers
		(0 "F.Cu" signal)
		(4 "In1.Cu" power)
		(6 "In2.Cu" mixed)
		(8 "In3.Cu" power)
		(10 "In4.Cu" mixed)
		(12 "In5.Cu" power)
		(14 "In6.Cu" mixed)
		(16 "In7.Cu" power)
		(18 "In8.Cu" power)
		(20 "In9.Cu" mixed)
		(22 "In10.Cu" power)
		(2 "B.Cu" signal)
		(9 "F.Adhes" user "F.Adhesive")
		(11 "B.Adhes" user "B.Adhesive")
		(13 "F.Paste" user)
		(15 "B.Paste" user)
		(5 "F.SilkS" user "F.Silkscreen")
		(7 "B.SilkS" user "B.Silkscreen")
		(1 "F.Mask" user)
		(3 "B.Mask" user)
		(17 "Dwgs.User" user "User.Drawings")
		(19 "Cmts.User" user "User.Comments")
		(21 "Eco1.User" user "User.Eco1")
		(23 "Eco2.User" user "User.Eco2")
		(25 "Edge.Cuts" user)
		(27 "Margin" user)
		(31 "F.CrtYd" user "F.Courtyard")
		(29 "B.CrtYd" user "B.Courtyard")
		(35 "F.Fab" user)
		(33 "B.Fab" user)
	)
	(footprint "antmicro-footprints:R_0402_1005Metric"
		(layer "B.Cu")
		(at 221.03 182.995)
		(descr "Resistor SMD 0402")
		(tags "resistor SMD 0402")
		(property "Reference" "R189"
			(at -3.83 0.505 0)
			(layer "B.SilkS")
			(effects
				(font
					(size 0.7 0.7)
					(thickness 0.15)
				)
				(justify right bottom mirror)
			)
		)
		(property "Value" "R_60k4_0402"
			(at -1.011843 -1.772047 0)
			(layer "B.Fab")
			(effects
				(font
					(size 0.7 0.7)
					(thickness 0.15)
				)
				(justify right bottom mirror)
			)
		)
		(property "Datasheet" "https://www.bourns.com/docs/product-datasheets/cr.pdf"
			(at 0 0 0)
			(layer "F.Fab")
			(hide yes)
			(effects
				(font
					(size 1.27 1.27)
					(thickness 0.15)
				)
			)
		)
		(property "MPN" "CR0402-FX-6042GLF"
			(at 0 0 0)
			(unlocked yes)
			(layer "B.Fab")
			(hide yes)
			(effects
				(font
					(size 1 1)
					(thickness 0.15)
				)
				(justify mirror)
			)
		)
		(property "Manufacturer" "Bourns"
			(at 0 0 0)
			(unlocked yes)
			(layer "B.Fab")
			(hide yes)
			(effects
				(font
					(size 1 1)
					(thickness 0.15)
				)
				(justify mirror)
			)
		)
		(property "License" "Apache-2.0"
			(at 0 0 0)
			(unlocked yes)
			(layer "B.Fab")
			(hide yes)
			(effects
				(font
					(size 1 1)
					(thickness 0.15)
				)
				(justify mirror)
			)
		)
		(property "Author" "Antmicro"
			(at 0 0 0)
			(unlocked yes)
			(layer "B.Fab")
			(hide yes)
			(effects
				(font
					(size 1 1)
					(thickness 0.15)
				)
				(justify mirror)
			)
		)
		(property "Val" "60k4"
			(at 0 0 0)
			(unlocked yes)
			(layer "B.Fab")
			(hide yes)
			(effects
				(font
					(size 1 1)
					(thickness 0.15)
				)
				(justify mirror)
			)
		)
		(property "Tolerance" "1%"
			(at 0 0 0)
			(unlocked yes)
			(layer "B.Fab")
			(hide yes)
			(effects
				(font
					(size 1 1)
					(thickness 0.15)
				)
				(justify mirror)
			)
		)
		(sheetname "/Supply/DC-DC VCCINT/")
		(sheetfile "dc-dc-vccint.kicad_sch")
		(attr smd)
		(fp_rect
			(start -0.925 0.47)
			(end 0.925 -0.47)
			(stroke
				(width 0.05)
				(type default)
			)
			(fill no)
			(layer "B.CrtYd")
		)
		(fp_rect
			(start -0.5 0.25)
			(end 0.5 -0.25)
			(stroke
				(width 0.15)
				(type solid)
			)
			(fill no)
			(layer "B.Fab")
		)
		(fp_text user "License: Apache-2.0"
			(at -0.95 -5.169 180)
			(layer "B.Fab")
			(effects
				(font
					(size 0.7 0.7)
					(thickness 0.15)
				)
				(justify left bottom mirror)
			)
		)
		(fp_text user "Author: Antmicro"
			(at -0.95 -4.169 180)
			(layer "B.Fab")
			(effects
				(font
					(size 0.7 0.7)
					(thickness 0.15)
				)
				(justify left bottom mirror)
			)
		)
		(fp_text user "${REFERENCE}"
			(at -0.95 -3.168 180)
			(layer "B.Fab")
			(effects
				(font
					(size 0.7 0.7)
					(thickness 0.15)
				)
				(justify left bottom mirror)
			)
		)
		(pad "1" smd roundrect
			(at -0.48 0)
			(size 0.59 0.64)
			(layers "B.Cu" "B.Mask" "B.Paste")
			(roundrect_rratio 0.25)
			(net 1 "GND")
			(pintype "passive")
		)
		(pad "2" smd roundrect
			(at 0.48 0)
			(size 0.59 0.64)
			(layers "B.Cu" "B.Mask" "B.Paste")
			(roundrect_rratio 0.25)
			(net 725 "Net-(U4-I_{REF})")
			(pintype "passive")
		)
	)
	(footprint "antmicro-footprints:C_0402_1005Metric_EIA"
		(layer "B.Cu")
		(at 192 150.502 -90)
		(descr "Capacitor SMD 0402 (1005 Metric), square (rectangular) end terminal, IPC_7351 nominal, (Body size source: IPC-SM-782 page 76, https://www.pcb-3d.com/wordpress/wp-content/uploads/ipc-sm-782a_amendment_1_and_2.pdf)")
		(tags "capacitor 0402")
		(property "Reference" "C243"
			(at -12.227 30.65 90)
			(layer "B.SilkS")
			(effects
				(font
					(size 0.7 0.7)
					(thickness 0.15)
				)
				(justify left bottom mirror)
			)
		)
		(property "Value" "C_10u_10V_0402"
			(at 0 -1.169 90)
			(layer "B.Fab")
			(effects
				(font
					(size 0.7 0.7)
					(thickness 0.15)
				)
				(justify left bottom mirror)
			)
		)
		(property "Datasheet" "https://www.murata.com/products/productdetail?partno=GRM155R61A106ME11%23"
			(at 0 0 270)
			(layer "F.Fab")
			(hide yes)
			(effects
				(font
					(size 1.27 1.27)
					(thickness 0.15)
				)
			)
		)
		(property "MPN" "GRM155R61A106ME11D"
			(at 0 0 270)
			(unlocked yes)
			(layer "B.Fab")
			(hide yes)
			(effects
				(font
					(size 1 1)
					(thickness 0.15)
				)
				(justify mirror)
			)
		)
		(property "Manufacturer" "Murata"
			(at 0 0 270)
			(unlocked yes)
			(layer "B.Fab")
			(hide yes)
			(effects
				(font
					(size 1 1)
					(thickness 0.15)
				)
				(justify mirror)
			)
		)
		(property "License" "Apache-2.0"
			(at 0 0 270)
			(unlocked yes)
			(layer "B.Fab")
			(hide yes)
			(effects
				(font
					(size 1 1)
					(thickness 0.15)
				)
				(justify mirror)
			)
		)
		(property "Author" "Antmicro"
			(at 0 0 270)
			(unlocked yes)
			(layer "B.Fab")
			(hide yes)
			(effects
				(font
					(size 1 1)
					(thickness 0.15)
				)
				(justify mirror)
			)
		)
		(property "Val" "10u"
			(at 0 0 270)
			(unlocked yes)
			(layer "B.Fab")
			(hide yes)
			(effects
				(font
					(size 1 1)
					(thickness 0.15)
				)
				(justify mirror)
			)
		)
		(property "Voltage" "10V"
			(at 0 0 270)
			(unlocked yes)
			(layer "B.Fab")
			(hide yes)
			(effects
				(font
					(size 1 1)
					(thickness 0.15)
				)
				(justify mirror)
			)
		)
		(property "Dielectric" "X5R"
			(at 0 0 270)
			(unlocked yes)
			(layer "B.Fab")
			(hide yes)
			(effects
				(font
					(size 1 1)
					(thickness 0.15)
				)
				(justify mirror)
			)
		)
		(sheetname "/FPGA power/")
		(sheetfile "fpga-power.kicad_sch")
		(attr smd)
		(fp_rect
			(start -0.95 0.45)
			(end 0.95 -0.45)
			(stroke
				(width 0.05)
				(type default)
			)
			(fill no)
			(layer "B.CrtYd")
		)
		(fp_line
			(start -0.5 0.25)
			(end 0.498 0.25)
			(stroke
				(width 0.15)
				(type solid)
			)
			(layer "B.Fab")
		)
		(fp_line
			(start 0.498 0.25)
			(end 0.498 -0.248)
			(stroke
				(width 0.15)
				(type solid)
			)
			(layer "B.Fab")
		)
		(fp_line
			(start -0.5 -0.248)
			(end -0.5 0.25)
			(stroke
				(width 0.15)
				(type solid)
			)
			(layer "B.Fab")
		)
		(fp_line
			(start 0.498 -0.248)
			(end -0.5 -0.248)
			(stroke
				(width 0.15)
				(type solid)
			)
			(layer "B.Fab")
		)
		(fp_text user "License: Apache-2.0"
			(at -0.9656 -4.369 90)
			(layer "B.Fab")
			(effects
				(font
					(size 0.7 0.7)
					(thickness 0.15)
				)
				(justify left bottom mirror)
			)
		)
		(fp_text user "${REFERENCE}"
			(at -0.9656 -3.169 90)
			(layer "B.Fab")
			(effects
				(font
					(size 0.7 0.7)
					(thickness 0.15)
				)
				(justify left bottom mirror)
			)
		)
		(fp_text user "Author: Antmicro"
			(at -0.9656 -5.569 90)
			(layer "B.Fab")
			(effects
				(font
					(size 0.7 0.7)
					(thickness 0.15)
				)
				(justify left bottom mirror)
			)
		)
		(pad "1" smd roundrect
			(at -0.5 0 180)
			(size 0.6 0.6)
			(layers "B.Cu" "B.Mask" "B.Paste")
			(roundrect_rratio 0.25)
			(net 1 "GND")
			(pintype "passive")
		)
		(pad "2" smd roundrect
			(at 0.498 0 270)
			(size 0.6 0.6)
			(layers "B.Cu" "B.Mask" "B.Paste")
			(roundrect_rratio 0.25)
			(net 553 "+0V85")
			(pintype "passive")
		)
	)
	(footprint "antmicro-footprints:C_0402_1005Metric"
		(layer "B.Cu")
		(at 167.65 193.299501 90)
		(descr "Capacitor SMD 0402")
		(tags "capacitor SMD 0402")
		(property "Reference" "C228"
			(at 0.994 0.403501 90)
			(layer "B.SilkS")
			(effects
				(font
					(size 0.7 0.7)
					(thickness 0.15)
				)
				(justify right bottom mirror)
			)
		)
		(property "Value" "C_100n_0402"
			(at -1.022927 -2.155213 90)
			(layer "B.Fab")
			(effects
				(font
					(size 0.7 0.7)
					(thickness 0.15)
				)
				(justify right bottom mirror)
			)
		)
		(property "Datasheet" "https://www.murata.com/products/productdetail?partno=GRM155R61H104KE14%23"
			(at 0 0 90)
			(layer "F.Fab")
			(hide yes)
			(effects
				(font
					(size 1.27 1.27)
					(thickness 0.15)
				)
			)
		)
		(property "Manufacturer" "Murata"
			(at 0 0 90)
			(unlocked yes)
			(layer "B.Fab")
			(hide yes)
			(effects
				(font
					(size 1 1)
					(thickness 0.15)
				)
				(justify mirror)
			)
		)
		(property "MPN" "GRM155R61H104KE14D"
			(at 0 0 90)
			(unlocked yes)
			(layer "B.Fab")
			(hide yes)
			(effects
				(font
					(size 1 1)
					(thickness 0.15)
				)
				(justify mirror)
			)
		)
		(property "Val" "100n"
			(at 0 0 90)
			(unlocked yes)
			(layer "B.Fab")
			(hide yes)
			(effects
				(font
					(size 1 1)
					(thickness 0.15)
				)
				(justify mirror)
			)
		)
		(property "License" "Apache-2.0"
			(at 0 0 90)
			(unlocked yes)
			(layer "B.Fab")
			(hide yes)
			(effects
				(font
					(size 1 1)
					(thickness 0.15)
				)
				(justify mirror)
			)
		)
		(property "Author" "Antmicro"
			(at 0 0 90)
			(unlocked yes)
			(layer "B.Fab")
			(hide yes)
			(effects
				(font
					(size 1 1)
					(thickness 0.15)
				)
				(justify mirror)
			)
		)
		(property "Voltage" "50V"
			(at 0 0 90)
			(unlocked yes)
			(layer "B.Fab")
			(hide yes)
			(effects
				(font
					(size 1 1)
					(thickness 0.15)
				)
				(justify mirror)
			)
		)
		(property "Dielectric" "X5R"
			(at 0 0 90)
			(unlocked yes)
			(layer "B.Fab")
			(hide yes)
			(effects
				(font
					(size 1 1)
					(thickness 0.15)
				)
				(justify mirror)
			)
		)
		(sheetname "/FPGA MGT Interface/")
		(sheetfile "fpga-mgt.kicad_sch")
		(attr smd)
		(fp_rect
			(start -0.925 0.47)
			(end 0.925 -0.47)
			(stroke
				(width 0.05)
				(type default)
			)
			(fill no)
			(layer "B.CrtYd")
		)
		(fp_line
			(start 0.504 -0.248)
			(end -0.494 -0.248)
			(stroke
				(width 0.15)
				(type solid)
			)
			(layer "B.Fab")
		)
		(fp_line
			(start -0.494 -0.248)
			(end -0.494 0.25)
			(stroke
				(width 0.15)
				(type solid)
			)
			(layer "B.Fab")
		)
		(fp_line
			(start 0.504 0.25)
			(end 0.504 -0.248)
			(stroke
				(width 0.15)
				(type solid)
			)
			(layer "B.Fab")
		)
		(fp_line
			(start -0.494 0.25)
			(end 0.504 0.25)
			(stroke
				(width 0.15)
				(type solid)
			)
			(layer "B.Fab")
		)
		(fp_text user "Author: Antmicro"
			(at -0.939 -3.399 270)
			(layer "B.Fab")
			(effects
				(font
					(size 0.7 0.7)
					(thickness 0.15)
				)
				(justify left bottom mirror)
			)
		)
		(fp_text user "${REFERENCE}"
			(at -0.939 -4.599 270)
			(layer "B.Fab")
			(effects
				(font
					(size 0.7 0.7)
					(thickness 0.15)
				)
				(justify left bottom mirror)
			)
		)
		(fp_text user "License: Apache-2.0"
			(at -0.939 -5.799 270)
			(layer "B.Fab")
			(effects
				(font
					(size 0.7 0.7)
					(thickness 0.15)
				)
				(justify left bottom mirror)
			)
		)
		(pad "1" smd roundrect
			(at -0.48 0 90)
			(size 0.59 0.64)
			(layers "B.Cu" "B.Mask" "B.Paste")
			(roundrect_rratio 0.25)
			(net 19 "/FPGA MGT Interface/PCIE.TXD1_P")
			(pintype "passive")
		)
		(pad "2" smd roundrect
			(at 0.48 0 90)
			(size 0.59 0.64)
			(layers "B.Cu" "B.Mask" "B.Paste")
			(roundrect_rratio 0.25)
			(net 20 "/FPGA MGT Interface/GTY_225_TX2_P")
			(pintype "passive")
		)
	)
	(footprint "antmicro-footprints:C_0402_1005Metric_EIA"
		(layer "B.Cu")
		(at 197 162.5 90)
		(descr "Capacitor SMD 0402 (1005 Metric), square (rectangular) end terminal, IPC_7351 nominal, (Body size source: IPC-SM-782 page 76, https://www.pcb-3d.com/wordpress/wp-content/uploads/ipc-sm-782a_amendment_1_and_2.pdf)")
		(tags "capacitor 0402")
		(property "Reference" "C106"
			(at -3.95 0.2 90)
			(layer "B.SilkS")
			(effects
				(font
					(size 0.7 0.7)
					(thickness 0.15)
				)
				(justify right bottom mirror)
			)
		)
		(property "Value" "C_100n_0402"
			(at 0 -1.169 90)
			(layer "B.Fab")
			(effects
				(font
					(size 0.7 0.7)
					(thickness 0.15)
				)
				(justify right bottom mirror)
			)
		)
		(property "Datasheet" "https://www.murata.com/products/productdetail?partno=GRM155R61H104KE14%23"
			(at 0 0 90)
			(layer "F.Fab")
			(hide yes)
			(effects
				(font
					(size 1.27 1.27)
					(thickness 0.15)
				)
			)
		)
		(property "MPN" "GRM155R61H104KE14D"
			(at 0 0 90)
			(unlocked yes)
			(layer "B.Fab")
			(hide yes)
			(effects
				(font
					(size 1 1)
					(thickness 0.15)
				)
				(justify mirror)
			)
		)
		(property "Manufacturer" "Murata"
			(at 0 0 90)
			(unlocked yes)
			(layer "B.Fab")
			(hide yes)
			(effects
				(font
					(size 1 1)
					(thickness 0.15)
				)
				(justify mirror)
			)
		)
		(property "License" "Apache-2.0"
			(at 0 0 90)
			(unlocked yes)
			(layer "B.Fab")
			(hide yes)
			(effects
				(font
					(size 1 1)
					(thickness 0.15)
				)
				(justify mirror)
			)
		)
		(property "Author" "Antmicro"
			(at 0 0 90)
			(unlocked yes)
			(layer "B.Fab")
			(hide yes)
			(effects
				(font
					(size 1 1)
					(thickness 0.15)
				)
				(justify mirror)
			)
		)
		(property "Val" "100n"
			(at 0 0 90)
			(unlocked yes)
			(layer "B.Fab")
			(hide yes)
			(effects
				(font
					(size 1 1)
					(thickness 0.15)
				)
				(justify mirror)
			)
		)
		(property "Voltage" "50V"
			(at 0 0 90)
			(unlocked yes)
			(layer "B.Fab")
			(hide yes)
			(effects
				(font
					(size 1 1)
					(thickness 0.15)
				)
				(justify mirror)
			)
		)
		(property "Dielectric" "X5R"
			(at 0 0 90)
			(unlocked yes)
			(layer "B.Fab")
			(hide yes)
			(effects
				(font
					(size 1 1)
					(thickness 0.15)
				)
				(justify mirror)
			)
		)
		(sheetname "/FPGA power/")
		(sheetfile "fpga-power.kicad_sch")
		(attr smd)
		(fp_rect
			(start -0.95 0.45)
			(end 0.95 -0.45)
			(stroke
				(width 0.05)
				(type default)
			)
			(fill no)
			(layer "B.CrtYd")
		)
		(fp_line
			(start 0.498 -0.248)
			(end -0.5 -0.248)
			(stroke
				(width 0.15)
				(type solid)
			)
			(layer "B.Fab")
		)
		(fp_line
			(start -0.5 -0.248)
			(end -0.5 0.25)
			(stroke
				(width 0.15)
				(type solid)
			)
			(layer "B.Fab")
		)
		(fp_line
			(start 0.498 0.25)
			(end 0.498 -0.248)
			(stroke
				(width 0.15)
				(type solid)
			)
			(layer "B.Fab")
		)
		(fp_line
			(start -0.5 0.25)
			(end 0.498 0.25)
			(stroke
				(width 0.15)
				(type solid)
			)
			(layer "B.Fab")
		)
		(fp_text user "License: Apache-2.0"
			(at -0.9656 -4.369 270)
			(layer "B.Fab")
			(effects
				(font
					(size 0.7 0.7)
					(thickness 0.15)
				)
				(justify left bottom mirror)
			)
		)
		(fp_text user "Author: Antmicro"
			(at -0.9656 -5.569 270)
			(layer "B.Fab")
			(effects
				(font
					(size 0.7 0.7)
					(thickness 0.15)
				)
				(justify left bottom mirror)
			)
		)
		(fp_text user "${REFERENCE}"
			(at -0.9656 -3.169 270)
			(layer "B.Fab")
			(effects
				(font
					(size 0.7 0.7)
					(thickness 0.15)
				)
				(justify left bottom mirror)
			)
		)
		(pad "1" smd roundrect
			(at -0.5 0)
			(size 0.6 0.6)
			(layers "B.Cu" "B.Mask" "B.Paste")
			(roundrect_rratio 0.25)
			(net 1 "GND")
			(pintype "passive")
		)
		(pad "2" smd roundrect
			(at 0.498 0 90)
			(size 0.6 0.6)
			(layers "B.Cu" "B.Mask" "B.Paste")
			(roundrect_rratio 0.25)
			(net 172 "+1V2_MGTAVTT")
			(pintype "passive")
		)
	)
	(footprint "antmicro-footprints:C_0402_1005Metric_EIA"
		(layer "B.Cu")
		(at 186 158.499999 90)
		(descr "Capacitor SMD 0402 (1005 Metric), square (rectangular) end terminal, IPC_7351 nominal, (Body size source: IPC-SM-782 page 76, https://www.pcb-3d.com/wordpress/wp-content/uploads/ipc-sm-782a_amendment_1_and_2.pdf)")
		(tags "capacitor 0402")
		(property "Reference" "C51"
			(at 9.524999 -30.625 90)
			(layer "B.SilkS")
			(effects
				(font
					(size 0.7 0.7)
					(thickness 0.15)
				)
				(justify right bottom mirror)
			)
		)
		(property "Value" "C_1u_25V_0402"
			(at 0 -1.169 90)
			(layer "B.Fab")
			(effects
				(font
					(size 0.7 0.7)
					(thickness 0.15)
				)
				(justify right bottom mirror)
			)
		)
		(property "Datasheet" "https://www.murata.com/products/productdetail?partno=GRM155R61E105KE11%23"
			(at 0 0 90)
			(layer "F.Fab")
			(hide yes)
			(effects
				(font
					(size 1.27 1.27)
					(thickness 0.15)
				)
			)
		)
		(property "MPN" "GRM155R61E105KE11J"
			(at 0 0 90)
			(unlocked yes)
			(layer "B.Fab")
			(hide yes)
			(effects
				(font
					(size 1 1)
					(thickness 0.15)
				)
				(justify mirror)
			)
		)
		(property "Manufacturer" "Murata"
			(at 0 0 90)
			(unlocked yes)
			(layer "B.Fab")
			(hide yes)
			(effects
				(font
					(size 1 1)
					(thickness 0.15)
				)
				(justify mirror)
			)
		)
		(property "License" "Apache-2.0"
			(at 0 0 90)
			(unlocked yes)
			(layer "B.Fab")
			(hide yes)
			(effects
				(font
					(size 1 1)
					(thickness 0.15)
				)
				(justify mirror)
			)
		)
		(property "Author" "Antmicro"
			(at 0 0 90)
			(unlocked yes)
			(layer "B.Fab")
			(hide yes)
			(effects
				(font
					(size 1 1)
					(thickness 0.15)
				)
				(justify mirror)
			)
		)
		(property "Val" "1u"
			(at 0 0 90)
			(unlocked yes)
			(layer "B.Fab")
			(hide yes)
			(effects
				(font
					(size 1 1)
					(thickness 0.15)
				)
				(justify mirror)
			)
		)
		(property "Voltage" "25V"
			(at 0 0 90)
			(unlocked yes)
			(layer "B.Fab")
			(hide yes)
			(effects
				(font
					(size 1 1)
					(thickness 0.15)
				)
				(justify mirror)
			)
		)
		(property "Dielectric" "X5R"
			(at 0 0 90)
			(unlocked yes)
			(layer "B.Fab")
			(hide yes)
			(effects
				(font
					(size 1 1)
					(thickness 0.15)
				)
				(justify mirror)
			)
		)
		(sheetname "/FPGA power/")
		(sheetfile "fpga-power.kicad_sch")
		(attr smd)
		(fp_rect
			(start -0.95 0.45)
			(end 0.95 -0.45)
			(stroke
				(width 0.05)
				(type default)
			)
			(fill no)
			(layer "B.CrtYd")
		)
		(fp_line
			(start 0.498 -0.248)
			(end -0.5 -0.248)
			(stroke
				(width 0.15)
				(type solid)
			)
			(layer "B.Fab")
		)
		(fp_line
			(start -0.5 -0.248)
			(end -0.5 0.25)
			(stroke
				(width 0.15)
				(type solid)
			)
			(layer "B.Fab")
		)
		(fp_line
			(start 0.498 0.25)
			(end 0.498 -0.248)
			(stroke
				(width 0.15)
				(type solid)
			)
			(layer "B.Fab")
		)
		(fp_line
			(start -0.5 0.25)
			(end 0.498 0.25)
			(stroke
				(width 0.15)
				(type solid)
			)
			(layer "B.Fab")
		)
		(fp_text user "Author: Antmicro"
			(at -0.9656 -5.569 270)
			(layer "B.Fab")
			(effects
				(font
					(size 0.7 0.7)
					(thickness 0.15)
				)
				(justify left bottom mirror)
			)
		)
		(fp_text user "License: Apache-2.0"
			(at -0.9656 -4.369 270)
			(layer "B.Fab")
			(effects
				(font
					(size 0.7 0.7)
					(thickness 0.15)
				)
				(justify left bottom mirror)
			)
		)
		(fp_text user "${REFERENCE}"
			(at -0.9656 -3.169 270)
			(layer "B.Fab")
			(effects
				(font
					(size 0.7 0.7)
					(thickness 0.15)
				)
				(justify left bottom mirror)
			)
		)
		(pad "1" smd roundrect
			(at -0.5 0)
			(size 0.6 0.6)
			(layers "B.Cu" "B.Mask" "B.Paste")
			(roundrect_rratio 0.25)
			(net 1 "GND")
			(pintype "passive")
		)
		(pad "2" smd roundrect
			(at 0.498 0 90)
			(size 0.6 0.6)
			(layers "B.Cu" "B.Mask" "B.Paste")
			(roundrect_rratio 0.25)
			(net 553 "+0V85")
			(pintype "passive")
		)
	)
)
